FILE_TYPE = MACRO_DRAWING;
SET COLOR_WIRE YELLOW;
SET COLOR_PROP ORANGE;
SET COLOR_DOT WHITE;
SET COLOR_ARC YELLOW;
SET COLOR_BODY GREEN;
SET COLOR_NOTE PURPLE;
SET PROP_DISPLAY VALUE;
SET PAGE_NUMBER P207;
FORCEADD MOSFET_N..1
(-1525 4525);
FORCEPROP 1 LAST PART_NUMBER BAM138K0000
J 0
(-1353 4386);
DISPLAY 0.723404 (-1353 4386);
PAINT GREEN (-1353 4386);
DISPLAY INVISIBLE (-1353 4386);
FORCEPROP 1 LAST MATERIAL IC
J 0
(-1353 4306);
DISPLAY 0.723404 (-1353 4306);
PAINT GREEN (-1353 4306);
FORCEPROP 1 LAST VALUE BSS138K
J 0
(-1353 4546);
DISPLAY 0.723404 (-1353 4546);
PAINT GREEN (-1353 4546);
FORCEPROP 2 LAST PATH I236
J 0
(-1350 4600);
DISPLAY 1.021277 (-1350 4600);
FORCEPROP 1 LAST $LOCATION U89
J 0
(-1353 4466);
DISPLAY 0.723404 (-1353 4466);
PAINT GREEN (-1353 4466);
FORCEPROP 1 LASTPIN (-1475 4625) $PN D
R 1
J 0
(-1475 4618);
DISPLAY 0.659574 (-1475 4618);
PAINT GREEN (-1475 4618);
FORCEPROP 1 LASTPIN (-1625 4425) $PN G
J 2
(-1615 4428);
DISPLAY 0.659574 (-1615 4428);
PAINT GREEN (-1615 4428);
FORCEPROP 1 LASTPIN (-1475 4325) $PN S
R 1
J 2
(-1475 4338);
DISPLAY 0.659574 (-1475 4338);
PAINT GREEN (-1475 4338);
FORCEPROP 0 LAST MANUF_PN BSS138K
J 0
(-1350 4400);
DISPLAY 1.021277 (-1350 4400);
DISPLAY INVISIBLE (-1350 4400);
FORCEPROP 1 LAST PACK_TYPE SMLF
J 0
(-1500 4275);
DISPLAY 0.723404 (-1500 4275);
PAINT GREEN (-1500 4275);
DISPLAY INVISIBLE (-1500 4275);
FORCEPROP 2 LAST CDS_LIB pure_quanta
J 0
(-1525 4525);
PAINT MONO (-1525 4525);
DISPLAY INVISIBLE (-1525 4525);
FORCEPROP 1 LAST CDS_LMAN_SYM_OUTLINE -50,50,100,-150
J 0
(-1525 4525);
DISPLAY 0.468085 (-1525 4525);
PAINT GREEN (-1525 4525);
DISPLAY INVISIBLE (-1525 4525);
FORCEPROP 2 LAST CDS_LOCATION U89
J 0
(-1350 4600);
DISPLAY 1.021277 (-1350 4600);
DISPLAY INVISIBLE (-1350 4600);
FORCEPROP 2 LAST $SEC 1
J 0
(-1350 4600);
DISPLAY 0.680851 (-1350 4600);
PAINT MONO (-1350 4600);
DISPLAY INVISIBLE (-1350 4600);
FORCEPROP 2 LAST CDS_SEC 1
J 0
(-1350 4600);
DISPLAY 1.021277 (-1350 4600);
DISPLAY INVISIBLE (-1350 4600);
FORCEADD UNIVERSAL_GND..1
(-1475 4125);
FORCEPROP 3 LASTPIN (-1475 4175) SIG_NAME GND\g
J 0
(-1465 4185);
DISPLAY 0.659574 (-1465 4185);
PAINT MONO (-1465 4185);
DISPLAY INVISIBLE (-1465 4185);
FORCEPROP 2 LAST CDS_LIB logical_power
J 0
(-1475 4125);
PAINT MONO (-1475 4125);
DISPLAY INVISIBLE (-1475 4125);
FORCEPROP 1 LAST HDL_POWER GND
J 1
(-1450 4050);
DISPLAY 0.872340 (-1450 4050);
PAINT GREEN (-1450 4050);
DISPLAY INVISIBLE (-1450 4050);
FORCEPROP 1 LAST PATH I237
J 0
(-1400 4125);
DISPLAY 0.872340 (-1400 4125);
PAINT AQUA (-1400 4125);
DISPLAY INVISIBLE (-1400 4125);
FORCEPROP 2 LAST ROOM IO_SLOT
J 1
(-1700 4200);
DISPLAY 0.744681 (-1700 4200);
DISPLAY INVISIBLE (-1700 4200);
FORCEADD OFFPAGE..4
R 2
(-3075 4425);
FORCEPROP 2 LAST $XR1 220 
J 0
(-3447 4425);
DISPLAY 0.638298 (-3447 4425);
PAINT MONO (-3447 4425);
FORCEPROP 2 LAST $XR0 215 
J 0
(-3327 4425);
DISPLAY 0.638298 (-3327 4425);
PAINT MONO (-3327 4425);
FORCEPROP 2 LAST CDS_LIB standard
J 0
(-3075 4425);
PAINT MONO (-3075 4425);
DISPLAY INVISIBLE (-3075 4425);
FORCEPROP 1 LAST OFFPAGE TRUE
J 2
(-3400 4300);
DISPLAY 0.872340 (-3400 4300);
DISPLAY INVISIBLE (-3400 4300);
FORCEPROP 1 LAST COMMENT_BODY TRUE
J 2
(-3050 4325);
DISPLAY 0.872340 (-3050 4325);
PAINT GREEN (-3050 4325);
DISPLAY INVISIBLE (-3050 4325);
FORCEPROP 2 LAST PATH I238
J 0
(-3345 4475);
DISPLAY 1.021277 (-3345 4475);
DISPLAY INVISIBLE (-3345 4475);
FORCEADD UNIVERSAL_POWER..1
(-4675 5050);
FORCEPROP 3 LASTPIN (-4675 5000) SIG_NAME P3V3_AUX\g
J 0
(-4665 5010);
DISPLAY 0.659574 (-4665 5010);
PAINT MONO (-4665 5010);
DISPLAY INVISIBLE (-4665 5010);
FORCEPROP 1 LAST HDL_POWER P3V3_AUX
J 1
(-4675 5100);
DISPLAY 0.872340 (-4675 5100);
PAINT GREEN (-4675 5100);
FORCEPROP 2 LAST CDS_LIB logical_power
J 0
(-4675 5050);
PAINT MONO (-4675 5050);
DISPLAY INVISIBLE (-4675 5050);
FORCEPROP 1 LAST PATH I240
J 0
(-4625 5075);
DISPLAY 0.872340 (-4625 5075);
PAINT AQUA (-4625 5075);
DISPLAY INVISIBLE (-4625 5075);
FORCEADD UNIVERSAL_GND..1
(1300 1625);
FORCEPROP 3 LASTPIN (1300 1675) SIG_NAME GND\g
J 0
(1310 1685);
DISPLAY 0.659574 (1310 1685);
PAINT MONO (1310 1685);
DISPLAY INVISIBLE (1310 1685);
FORCEPROP 2 LAST CDS_LIB logical_power
J 0
(1300 1625);
DISPLAY INVISIBLE (1300 1625);
FORCEPROP 1 LAST HDL_POWER GND
J 1
(1325 1550);
DISPLAY 0.872340 (1325 1550);
PAINT GREEN (1325 1550);
DISPLAY INVISIBLE (1325 1550);
FORCEPROP 1 LAST PATH I267
J 0
(1375 1625);
DISPLAY 0.872340 (1375 1625);
PAINT AQUA (1375 1625);
DISPLAY INVISIBLE (1375 1625);
FORCEPROP 2 LAST ROOM IO_SLOT
J 1
(1075 1700);
DISPLAY 0.744681 (1075 1700);
DISPLAY INVISIBLE (1075 1700);
FORCEADD Q_RES..1
(-50 950);
FORCEPROP 1 LAST PART_NUMBER CS02202JB09
J 0
(-200 1025);
DISPLAY 0.638298 (-200 1025);
DISPLAY INVISIBLE (-200 1025);
FORCEPROP 1 LAST PACK_TYPE 0402LF
J 0
(-200 1075);
DISPLAY 0.638298 (-200 1075);
FORCEPROP 1 LAST WATTAGE 1/16W
J 2
(150 1075);
DISPLAY 0.638298 (150 1075);
FORCEPROP 1 LAST VALUE 22
J 2
(150 950);
DISPLAY 0.638298 (150 950);
FORCEPROP 1 LAST MATERIAL CHIP
J 0
(250 950);
DISPLAY 0.638298 (250 950);
FORCEPROP 1 LAST TOLERANCE 5%
J 0
(175 950);
DISPLAY 0.638298 (175 950);
FORCEPROP 1 LAST $LOCATION R2339
J 0
(-325 950);
DISPLAY 0.638298 (-325 950);
FORCEPROP 1 LASTPIN (-150 950) $PN 1
J 0
(-138 962);
DISPLAY 0.787234 (-138 962);
PAINT MONO (-138 962);
FORCEPROP 1 LASTPIN (50 950) $PN 2
J 0
(12 962);
DISPLAY 0.787234 (12 962);
PAINT MONO (12 962);
FORCEPROP 2 LAST CDS_LIB pure_quanta
J 0
(-50 950);
DISPLAY INVISIBLE (-50 950);
FORCEPROP 1 LAST PATH I268
J 0
(-100 1100);
DISPLAY 0.978723 (-100 1100);
PAINT WHITE (-100 1100);
DISPLAY INVISIBLE (-100 1100);
FORCEPROP 0 LAST CDS_LOCATION R2339
J 0
(125 1125);
DISPLAY 1.021277 (125 1125);
DISPLAY INVISIBLE (125 1125);
FORCEPROP 0 LAST $SEC 1
J 0
(150 1125);
DISPLAY 0.680851 (150 1125);
PAINT MONO (150 1125);
DISPLAY INVISIBLE (150 1125);
FORCEPROP 0 LAST CDS_SEC 1
J 0
(125 1125);
DISPLAY 1.021277 (125 1125);
DISPLAY INVISIBLE (125 1125);
FORCEADD UNIVERSAL_GND..1
(450 825);
FORCEPROP 3 LASTPIN (450 875) SIG_NAME GND\g
J 0
(460 885);
DISPLAY 0.659574 (460 885);
PAINT MONO (460 885);
DISPLAY INVISIBLE (460 885);
FORCEPROP 2 LAST CDS_LIB logical_power
J 0
(450 825);
DISPLAY INVISIBLE (450 825);
FORCEPROP 1 LAST HDL_POWER GND
J 1
(475 750);
DISPLAY 0.872340 (475 750);
PAINT GREEN (475 750);
DISPLAY INVISIBLE (475 750);
FORCEPROP 1 LAST PATH I269
J 0
(525 825);
DISPLAY 0.872340 (525 825);
PAINT AQUA (525 825);
DISPLAY INVISIBLE (525 825);
FORCEPROP 2 LAST ROOM IO_SLOT
J 1
(225 900);
DISPLAY 0.744681 (225 900);
DISPLAY INVISIBLE (225 900);
FORCEADD UNIVERSAL_POWER..1
(-1425 2300);
FORCEPROP 3 LASTPIN (-1425 2250) SIG_NAME P3V3_AUX\g
J 0
(-1415 2260);
DISPLAY 0.659574 (-1415 2260);
PAINT MONO (-1415 2260);
DISPLAY INVISIBLE (-1415 2260);
FORCEPROP 1 LAST HDL_POWER P3V3_AUX
J 1
(-1425 2350);
DISPLAY 0.872340 (-1425 2350);
PAINT GREEN (-1425 2350);
FORCEPROP 2 LAST CDS_LIB logical_power
J 0
(-1425 2300);
PAINT MONO (-1425 2300);
DISPLAY INVISIBLE (-1425 2300);
FORCEPROP 1 LAST PATH I270
J 0
(-1375 2325);
DISPLAY 0.872340 (-1375 2325);
PAINT AQUA (-1375 2325);
DISPLAY INVISIBLE (-1375 2325);
FORCEADD MOSFET_NCH_GDS_ESD_PROTECTED..1
(-1450 1325);
FORCEPROP 1 LAST PART_NUMBER BAM70020002
J 0
(-1308 1237);
DISPLAY 0.723404 (-1308 1237);
PAINT GREEN (-1308 1237);
DISPLAY INVISIBLE (-1308 1237);
FORCEPROP 2 LAST VALUE 2N7002K
J 0
(-1300 1375);
DISPLAY 0.680851 (-1300 1375);
FORCEPROP 1 LAST MATERIAL IC
J 0
(-1308 1180);
DISPLAY 0.723404 (-1308 1180);
PAINT GREEN (-1308 1180);
FORCEPROP 2 LAST PART_TYPE SMLF
J 0
(-1300 1425);
DISPLAY 0.680851 (-1300 1425);
FORCEPROP 1 LAST LOCATION Q33
J 0
(-1308 1289);
DISPLAY 0.723404 (-1308 1289);
PAINT GREEN (-1308 1289);
FORCEPROP 0 LASTPIN (-1425 1525) $PN D
R 1
J 0
(-1435 1535);
DISPLAY 0.680851 (-1435 1535);
PAINT MONO (-1435 1535);
FORCEPROP 0 LASTPIN (-1625 1325) $PN G
J 2
(-1635 1335);
DISPLAY 0.680851 (-1635 1335);
PAINT MONO (-1635 1335);
FORCEPROP 0 LASTPIN (-1425 1125) $PN S
R 1
J 2
(-1435 1115);
DISPLAY 0.680851 (-1435 1115);
PAINT MONO (-1435 1115);
FORCEPROP 2 LAST CDS_LIB pure_quanta
J 0
(-1450 1325);
DISPLAY INVISIBLE (-1450 1325);
FORCEPROP 1 LAST CDS_LMAN_SYM_OUTLINE -125,150,125,-150
J 0
(-1450 1325);
DISPLAY 0.468085 (-1450 1325);
PAINT GREEN (-1450 1325);
DISPLAY INVISIBLE (-1450 1325);
FORCEPROP 1 LAST NEEDS_NO_SIZE TRUE
J 0
(-1325 1215);
DISPLAY 0.723404 (-1325 1215);
PAINT GREEN (-1325 1215);
DISPLAY INVISIBLE (-1325 1215);
FORCEPROP 1 LAST PATH I272
J 0
(-1325 1175);
DISPLAY 0.723404 (-1325 1175);
PAINT GREEN (-1325 1175);
DISPLAY INVISIBLE (-1325 1175);
FORCEPROP 0 LAST $SEC 1
J 0
(-1300 1475);
DISPLAY 0.680851 (-1300 1475);
PAINT MONO (-1300 1475);
DISPLAY INVISIBLE (-1300 1475);
FORCEPROP 0 LAST CDS_SEC 1
J 0
(-1300 1475);
DISPLAY 1.021277 (-1300 1475);
DISPLAY INVISIBLE (-1300 1475);
FORCEADD Q_RES..1
(-3150 1325);
FORCEPROP 1 LAST PART_NUMBER CS00002JB13
J 0
(-3250 1400);
DISPLAY 0.404255 (-3250 1400);
DISPLAY INVISIBLE (-3250 1400);
FORCEPROP 1 LAST TOLERANCE 5%
J 0
(-2950 1325);
DISPLAY 0.510638 (-2950 1325);
FORCEPROP 1 LAST MATERIAL CHIP
J 0
(-2875 1325);
DISPLAY 0.510638 (-2875 1325);
FORCEPROP 1 LAST WATTAGE 1/16W
J 2
(-3025 1425);
DISPLAY 0.404255 (-3025 1425);
FORCEPROP 1 LAST PACK_TYPE 0402LF
J 0
(-3250 1425);
DISPLAY 0.404255 (-3250 1425);
FORCEPROP 1 LAST VALUE 0
J 2
(-3000 1325);
DISPLAY 0.510638 (-3000 1325);
FORCEPROP 1 LAST $LOCATION R365
J 0
(-3400 1325);
DISPLAY 0.638298 (-3400 1325);
FORCEPROP 1 LASTPIN (-3250 1325) $PN 1
J 0
(-3238 1337);
DISPLAY 0.787234 (-3238 1337);
FORCEPROP 1 LASTPIN (-3050 1325) $PN 2
J 0
(-3088 1337);
DISPLAY 0.787234 (-3088 1337);
FORCEPROP 2 LAST CDS_LIB pure_quanta
J 0
(-3150 1325);
PAINT MONO (-3150 1325);
DISPLAY INVISIBLE (-3150 1325);
FORCEPROP 1 LAST PATH I273
J 0
(-3200 1475);
DISPLAY 0.978723 (-3200 1475);
PAINT WHITE (-3200 1475);
DISPLAY INVISIBLE (-3200 1475);
FORCEPROP 2 LAST CDS_LOCATION R365
J 0
(-3200 1525);
DISPLAY 1.021277 (-3200 1525);
DISPLAY INVISIBLE (-3200 1525);
FORCEPROP 2 LAST $SEC 1
J 0
(-3200 1525);
DISPLAY 0.680851 (-3200 1525);
PAINT MONO (-3200 1525);
DISPLAY INVISIBLE (-3200 1525);
FORCEPROP 2 LAST CDS_SEC 1
J 0
(-3200 1525);
DISPLAY 1.021277 (-3200 1525);
DISPLAY INVISIBLE (-3200 1525);
FORCEADD UNIVERSAL_POWER..1
(-4625 1875);
FORCEPROP 3 LASTPIN (-4625 1825) SIG_NAME P3V3_AUX\g
J 0
(-4615 1835);
DISPLAY 0.659574 (-4615 1835);
PAINT MONO (-4615 1835);
DISPLAY INVISIBLE (-4615 1835);
FORCEPROP 1 LAST HDL_POWER P3V3_AUX
J 1
(-4625 1925);
DISPLAY 0.872340 (-4625 1925);
PAINT GREEN (-4625 1925);
FORCEPROP 2 LAST CDS_LIB logical_power
J 0
(-4625 1875);
PAINT MONO (-4625 1875);
DISPLAY INVISIBLE (-4625 1875);
FORCEPROP 1 LAST PATH I274
J 0
(-4575 1900);
DISPLAY 0.872340 (-4575 1900);
PAINT AQUA (-4575 1900);
DISPLAY INVISIBLE (-4575 1900);
FORCEADD Q_RES..2
(-4625 1625);
FORCEPROP 1 LAST PART_NUMBER CS31002FB08
J 0
(-4585 1500);
DISPLAY 0.510638 (-4585 1500);
DISPLAY INVISIBLE (-4585 1500);
FORCEPROP 1 LAST WATTAGE 1/16W
J 0
(-4585 1600);
DISPLAY 0.510638 (-4585 1600);
FORCEPROP 1 LAST TOLERANCE 1%
J 0
(-4580 1650);
DISPLAY 0.510638 (-4580 1650);
FORCEPROP 1 LAST VALUE 10K
J 0
(-4580 1700);
DISPLAY 0.510638 (-4580 1700);
FORCEPROP 1 LAST MATERIAL CHIP
J 0
(-4585 1550);
DISPLAY 0.510638 (-4585 1550);
FORCEPROP 1 LAST PACK_TYPE 0402LF
J 0
(-4585 1450);
DISPLAY 0.510638 (-4585 1450);
FORCEPROP 1 LAST $LOCATION R1841
J 0
(-4580 1750);
DISPLAY 0.510638 (-4580 1750);
FORCEPROP 1 LASTPIN (-4625 1725) $PN 1
J 0
(-4620 1687);
DISPLAY 0.787234 (-4620 1687);
FORCEPROP 1 LASTPIN (-4625 1525) $PN 2
J 0
(-4620 1535);
DISPLAY 0.787234 (-4620 1535);
FORCEPROP 2 LAST CDS_LIB pure_quanta
J 0
(-4625 1625);
PAINT MONO (-4625 1625);
DISPLAY INVISIBLE (-4625 1625);
FORCEPROP 1 LAST PATH I275
J 0
(-4575 1800);
DISPLAY 0.978723 (-4575 1800);
PAINT WHITE (-4575 1800);
DISPLAY INVISIBLE (-4575 1800);
FORCEPROP 2 LAST CDS_LOCATION R1841
J 0
(-4575 1850);
DISPLAY 1.021277 (-4575 1850);
DISPLAY INVISIBLE (-4575 1850);
FORCEPROP 2 LAST $SEC 1
J 0
(-4575 1850);
DISPLAY 0.680851 (-4575 1850);
PAINT MONO (-4575 1850);
DISPLAY INVISIBLE (-4575 1850);
FORCEPROP 2 LAST CDS_SEC 1
J 0
(-4575 1850);
DISPLAY 1.021277 (-4575 1850);
DISPLAY INVISIBLE (-4575 1850);
FORCEADD OFFPAGE..4
R 2
(-4800 1325);
FORCEPROP 2 LAST $XR1 220 
J 0
(-5202 1325);
DISPLAY 0.638298 (-5202 1325);
PAINT MONO (-5202 1325);
FORCEPROP 2 LAST $XR0 215 
J 0
(-5082 1325);
DISPLAY 0.638298 (-5082 1325);
PAINT MONO (-5082 1325);
FORCEPROP 2 LAST CDS_LIB standard
J 0
(-4800 1325);
PAINT MONO (-4800 1325);
DISPLAY INVISIBLE (-4800 1325);
FORCEPROP 1 LAST OFFPAGE TRUE
J 2
(-5125 1200);
DISPLAY 0.872340 (-5125 1200);
DISPLAY INVISIBLE (-5125 1200);
FORCEPROP 1 LAST COMMENT_BODY TRUE
J 2
(-4775 1225);
DISPLAY 0.872340 (-4775 1225);
PAINT GREEN (-4775 1225);
DISPLAY INVISIBLE (-4775 1225);
FORCEPROP 2 LAST PATH I276
J 0
(-5050 1375);
DISPLAY 1.021277 (-5050 1375);
DISPLAY INVISIBLE (-5050 1375);
FORCEADD Q_LED..1
(-3050 4700);
FORCEPROP 1 LAST PART_NUMBER BEBL0172Z00
J 2
(-2875 4850);
DISPLAY 0.574468 (-2875 4850);
PAINT GREEN (-2875 4850);
DISPLAY INVISIBLE (-2875 4850);
FORCEPROP 1 LAST MATERIAL IC
J 2
(-3000 4900);
DISPLAY 0.723404 (-3000 4900);
PAINT GREEN (-3000 4900);
FORCEPROP 2 LAST MANUF_PN LTST-C281TBKT-5A
J 2
(-2875 4800);
DISPLAY 0.638298 (-2875 4800);
FORCEPROP 0 LAST PACK_TYPE SMLF
J 2
(-2875 4900);
DISPLAY 0.638298 (-2875 4900);
FORCEPROP 2 LAST COLOR LED_BLUE
J 2
(-2875 4950);
DISPLAY 0.638298 (-2875 4950);
FORCEPROP 1 LAST LOCATION D0
J 2
(-2950 4600);
DISPLAY 0.723404 (-2950 4600);
PAINT GREEN (-2950 4600);
FORCEPROP 0 LASTPIN (-3200 4700) $PN A
J 2
(-3210 4710);
DISPLAY 0.680851 (-3210 4710);
PAINT MONO (-3210 4710);
FORCEPROP 0 LASTPIN (-2900 4700) $PN C
J 0
(-2890 4710);
DISPLAY 0.680851 (-2890 4710);
PAINT MONO (-2890 4710);
FORCEPROP 2 LAST CDS_LIB pure_quanta
J 2
(-3050 4700);
DISPLAY INVISIBLE (-3050 4700);
FORCEPROP 1 LAST NEEDS_NO_SIZE TRUE
J 0
(-3072 4722);
DISPLAY 0.468085 (-3072 4722);
PAINT GREEN (-3072 4722);
DISPLAY INVISIBLE (-3072 4722);
FORCEPROP 1 LAST PATH I277
J 0
(-2925 4780);
DISPLAY 0.723404 (-2925 4780);
PAINT GREEN (-2925 4780);
DISPLAY INVISIBLE (-2925 4780);
FORCEPROP 0 LAST $SEC 1
J 0
(-2875 5000);
DISPLAY 0.680851 (-2875 5000);
PAINT MONO (-2875 5000);
DISPLAY INVISIBLE (-2875 5000);
FORCEPROP 0 LAST CDS_SEC 1
J 0
(-2875 5000);
DISPLAY 1.021277 (-2875 5000);
DISPLAY INVISIBLE (-2875 5000);
FORCEADD Q_RES..1
(-4250 4700);
FORCEPROP 1 LAST PART_NUMBER CS11302FB03
J 0
(-4475 4800);
DISPLAY 0.638298 (-4475 4800);
DISPLAY INVISIBLE (-4475 4800);
FORCEPROP 1 LAST VALUE 130
J 2
(-4000 4650);
DISPLAY 0.638298 (-4000 4650);
FORCEPROP 1 LAST TOLERANCE 1%
J 0
(-3975 4650);
DISPLAY 0.638298 (-3975 4650);
FORCEPROP 1 LAST PACK_TYPE 0402LF
J 0
(-3900 4650);
DISPLAY 0.638298 (-3900 4650);
FORCEPROP 1 LAST WATTAGE 1/16W
J 2
(-4100 4650);
DISPLAY 0.638298 (-4100 4650);
FORCEPROP 1 LAST MATERIAL CHIP
J 0
(-4400 4650);
DISPLAY 0.638298 (-4400 4650);
FORCEPROP 1 LAST LOCATION R1195
J 0
(-4475 4700);
DISPLAY 0.638298 (-4475 4700);
FORCEPROP 1 LASTPIN (-4350 4700) $PN 1
J 0
(-4338 4712);
DISPLAY 0.787234 (-4338 4712);
PAINT MONO (-4338 4712);
FORCEPROP 1 LASTPIN (-4150 4700) $PN 2
J 0
(-4188 4712);
DISPLAY 0.787234 (-4188 4712);
PAINT MONO (-4188 4712);
FORCEPROP 2 LAST CDS_LIB pure_quanta
J 0
(-4250 4700);
DISPLAY INVISIBLE (-4250 4700);
FORCEPROP 1 LAST PATH I278
J 0
(-4300 4850);
DISPLAY 0.978723 (-4300 4850);
PAINT WHITE (-4300 4850);
DISPLAY INVISIBLE (-4300 4850);
FORCEPROP 0 LAST $SEC 1
J 0
(-4350 4800);
DISPLAY 0.680851 (-4350 4800);
PAINT MONO (-4350 4800);
DISPLAY INVISIBLE (-4350 4800);
FORCEPROP 0 LAST CDS_SEC 1
J 0
(-4350 4800);
DISPLAY 1.021277 (-4350 4800);
DISPLAY INVISIBLE (-4350 4800);
FORCEADD Q_LED..1
(650 1775);
FORCEPROP 1 LAST PART_NUMBER BEYL0159Z00
J 0
(550 1910);
DISPLAY 0.723404 (550 1910);
PAINT GREEN (550 1910);
DISPLAY INVISIBLE (550 1910);
FORCEPROP 2 LAST PACK_TYPE SMLF
J 0
(550 2000);
DISPLAY 0.808511 (550 2000);
FORCEPROP 1 LAST MATERIAL IC
J 0
(550 1855);
DISPLAY 0.723404 (550 1855);
PAINT GREEN (550 1855);
FORCEPROP 2 LAST MANUF_PN LTST-C190KSKT-P
J 0
(550 2050);
DISPLAY 0.808511 (550 2050);
FORCEPROP 2 LAST COLOR LED_YELLOW
J 0
(550 2100);
DISPLAY 0.808511 (550 2100);
FORCEPROP 1 LAST LOCATION D6
J 0
(550 1960);
DISPLAY 0.723404 (550 1960);
PAINT GREEN (550 1960);
FORCEPROP 0 LASTPIN (500 1775) $PN A
J 2
(490 1785);
DISPLAY 0.680851 (490 1785);
PAINT MONO (490 1785);
FORCEPROP 0 LASTPIN (800 1775) $PN C
J 0
(810 1785);
DISPLAY 0.680851 (810 1785);
PAINT MONO (810 1785);
FORCEPROP 1 LAST NEEDS_NO_SIZE TRUE
J 0
(650 1775);
DISPLAY 0.468085 (650 1775);
PAINT GREEN (650 1775);
DISPLAY INVISIBLE (650 1775);
FORCEPROP 2 LAST CDS_LIB pure_quanta
J 0
(650 1775);
DISPLAY INVISIBLE (650 1775);
FORCEPROP 1 LAST PATH I279
J 0
(775 1855);
DISPLAY 0.723404 (775 1855);
PAINT GREEN (775 1855);
DISPLAY INVISIBLE (775 1855);
FORCEPROP 0 LAST $SEC 1
J 0
(550 2150);
DISPLAY 0.680851 (550 2150);
PAINT MONO (550 2150);
DISPLAY INVISIBLE (550 2150);
FORCEPROP 0 LAST CDS_SEC 1
J 0
(550 2150);
DISPLAY 1.021277 (550 2150);
DISPLAY INVISIBLE (550 2150);
FORCEADD Q_RES..2
(-1425 2000);
FORCEPROP 1 LAST PART_NUMBER CS12492FB02
J 0
(-1385 1875);
DISPLAY 0.638298 (-1385 1875);
DISPLAY INVISIBLE (-1385 1875);
FORCEPROP 1 LAST VALUE 249
J 0
(-1380 2075);
DISPLAY 0.638298 (-1380 2075);
FORCEPROP 1 LAST PACK_TYPE 0402LF
J 0
(-1385 1875);
DISPLAY 0.638298 (-1385 1875);
FORCEPROP 1 LAST MATERIAL CHIP
J 0
(-1385 1925);
DISPLAY 0.638298 (-1385 1925);
FORCEPROP 1 LAST WATTAGE 1/16W
J 0
(-1385 1975);
DISPLAY 0.638298 (-1385 1975);
FORCEPROP 1 LAST TOLERANCE 1%
J 0
(-1380 2025);
DISPLAY 0.638298 (-1380 2025);
FORCEPROP 1 LAST LOCATION R366
J 0
(-1380 2125);
DISPLAY 0.787234 (-1380 2125);
FORCEPROP 1 LASTPIN (-1425 2100) $PN 1
J 0
(-1420 2062);
DISPLAY 0.787234 (-1420 2062);
PAINT MONO (-1420 2062);
FORCEPROP 1 LASTPIN (-1425 1900) $PN 2
J 0
(-1420 1910);
DISPLAY 0.787234 (-1420 1910);
PAINT MONO (-1420 1910);
FORCEPROP 2 LAST CDS_LIB pure_quanta
J 0
(-1425 2000);
DISPLAY INVISIBLE (-1425 2000);
FORCEPROP 1 LAST PATH I280
J 0
(-1375 2175);
DISPLAY 0.978723 (-1375 2175);
PAINT WHITE (-1375 2175);
DISPLAY INVISIBLE (-1375 2175);
FORCEPROP 0 LAST $SEC 1
J 0
(-1375 2175);
DISPLAY 0.680851 (-1375 2175);
PAINT MONO (-1375 2175);
DISPLAY INVISIBLE (-1375 2175);
FORCEPROP 0 LAST CDS_SEC 1
J 0
(-1375 2175);
DISPLAY 1.021277 (-1375 2175);
DISPLAY INVISIBLE (-1375 2175);
FORCEADD QUANTA_TITLE_BLOCK_C..1
(3025 -850);
FORCEPROP 0 LAST CDS_CON_LAST_MODIFIED Fri Aug 25 14:03:39 2023
J 0
(1140 -835);
PAINT MONO (1140 -835);
DISPLAY INVISIBLE (1140 -835);
FORCEPROP 2 LAST CUSTOM_TXT_CDS <XR_PAGE_TITLE>
J 0
(-4865 4400);
DISPLAY 0.638298 (-4865 4400);
PAINT PINK (-4865 4400);
DISPLAY INVISIBLE (-4865 4400);
FORCEPROP 2 LAST CUSTOM_TXT_CDS <CON_LAST_MODIFIED>
J 0
(1125 -825);
DISPLAY 0.978723 (1125 -825);
FORCEPROP 2 LAST CUSTOM_TXT_CDS <Q_PROJ>
J 0
(643 -748);
DISPLAY 1.212766 (643 -748);
FORCEPROP 2 LAST CUSTOM_TXT_CDS <NAME_2>
J 0
(-150 -800);
FORCEPROP 2 LAST CUSTOM_TXT_CDS <NAME_1>
J 0
(-150 -675);
FORCEPROP 2 LAST CUSTOM_TXT_CDS <CON_PAGE_NUM> OF <CON_TOTAL_PAGES>
J 0
(2579 -832);
DISPLAY 0.978723 (2579 -832);
FORCEPROP 2 LAST CUSTOM_TXT_CDS <Q_REV>
J 0
(2841 -747);
DISPLAY 1.212766 (2841 -747);
FORCEPROP 2 LAST CUSTOM_TXT_CDS <Q_NUMBER>
J 0
(1622 -747);
DISPLAY 1.212766 (1622 -747);
FORCEPROP 1 LAST Q_TITLE MAIN FPGA / PFR - LEDS
J 0
(-6316 -824);
DISPLAY 1.957447 (-6316 -824);
PAINT GREEN (-6316 -824);
FORCEPROP 1 LAST Q_DEPT 
J 1
(-738 -801);
DISPLAY 1.957447 (-738 -801);
PAINT GREEN (-738 -801);
FORCEPROP 2 LAST CDS_XR_PAGE_TITLE CR-218 : @S9S_MB_2U_LIB.S9S_MB_2U(SCH_1):PAGE218
J 0
(-4865 4400);
DISPLAY 0.638298 (-4865 4400);
PAINT PINK (-4865 4400);
DISPLAY INVISIBLE (-4865 4400);
FORCEPROP 1 LAST COMMENT_BODY TRUE
J 0
(3037 -863);
DISPLAY 0.978723 (3037 -863);
PAINT GREEN (3037 -863);
DISPLAY INVISIBLE (3037 -863);
FORCEPROP 2 LAST CDS_LIB pure_quanta
J 0
(3025 -850);
PAINT MONO (3025 -850);
DISPLAY INVISIBLE (3025 -850);
FORCEPROP 1 LAST CDS_LMAN_SYM_OUTLINE -9475,6775,100,-125
J 0
(3025 -850);
DISPLAY 0.468085 (3025 -850);
PAINT GREEN (3025 -850);
DISPLAY INVISIBLE (3025 -850);
FORCEPROP 2 LAST PAGE_BORDER TRUE
J 0
(-4865 4400);
DISPLAY 0.638298 (-4865 4400);
PAINT PINK (-4865 4400);
DISPLAY INVISIBLE (-4865 4400);
WIRE 16 -1 (-1425 2250)(-1425 2100);
WIRE 16 -1 (-4675 5000)(-4675 4700);
WIRE 16 -1 (-4625 1725)(-4625 1825);
WIRE 16 -1 (1300 1775)(1300 1675);
WIRE 16 -1 (800 1775)(1300 1775);
WIRE 16 -1 (-1475 4325)(-1475 4175);
WIRE 16 -1 (450 950)(450 875);
WIRE 16 -1 (50 950)(450 950);
WIRE 16 2175 (-1475 1675)(1125 1675);
WIRE 16 2175 (1125 2175)(1125 1675);
WIRE 16 2175 (-1475 2175)(-1475 1675);
WIRE 16 2175 (-1475 2175)(1125 2175);
WIRE 16 -1 (-1425 1525)(-1425 1775);
WIRE 16 -1 (500 1775)(-1425 1775);
FORCEPROP 2 LAST SIG_NAME LED_CPU_RMCA_CATERR
J 0
(-385 1785);
DISPLAY 0.638298 (-385 1785);
PAINT WHITE (-385 1785);
WIRE 16 -1 (-1425 1900)(-1425 1775);
WIRE 16 2175 (-4525 5025)(-2825 5025);
WIRE 16 2175 (-2825 5025)(-2825 4600);
WIRE 16 2175 (-4525 5025)(-4525 4600);
WIRE 16 2175 (-4525 4600)(-2825 4600);
WIRE 16 -1 (-1475 4700)(-2900 4700);
FORCEPROP 0 LAST CDS_PHYS_NET_NAME FM_PLD_HEARTBEAT_LVC3_D
J 0
(-2800 4742);
PAINT MONO (-2800 4742);
DISPLAY INVISIBLE (-2800 4742);
FORCEPROP 0 LAST SIG_NAME FM_PLD_HEARTBEAT_LVC3_D
J 0
(-2725 4710);
DISPLAY 0.680851 (-2725 4710);
PAINT WHITE (-2725 4710);
WIRE 16 -1 (-1475 4625)(-1475 4700);
WIRE 16 -1 (-3025 4425)(-1625 4425);
FORCEPROP 0 LAST CDS_PHYS_NET_NAME FM_PLD_HEARTBEAT_LVC3
J 0
(-2925 4467);
PAINT MONO (-2925 4467);
DISPLAY INVISIBLE (-2925 4467);
FORCEPROP 0 LAST SIG_NAME FM_PLD_HEARTBEAT_LVC3
J 0
(-2850 4435);
DISPLAY 0.680851 (-2850 4435);
PAINT WHITE (-2850 4435);
WIRE 16 -1 (-150 950)(-1425 950);
FORCEPROP 2 LAST SIG_NAME LED_CPU_RMCA_CATERR_R
J 0
(-1235 960);
DISPLAY 0.638298 (-1235 960);
PAINT WHITE (-1235 960);
WIRE 16 -1 (-1425 1125)(-1425 950);
WIRE 16 -1 (-4150 4700)(-3200 4700);
FORCEPROP 2 LAST SIG_NAME PU_PLD_HEARTBEAT_LVC3
J 0
(-4110 4710);
DISPLAY 0.808511 (-4110 4710);
WIRE 16 -1 (-1625 1325)(-3050 1325);
FORCEPROP 0 LAST CDS_PHYS_NET_NAME CPU_RMCA_CATERR_LVT3_N
J 0
(-2900 1367);
PAINT MONO (-2900 1367);
DISPLAY INVISIBLE (-2900 1367);
FORCEPROP 0 LAST SIG_NAME CPU_RMCA_CATERR_LVT3_N
J 0
(-2610 1335);
DISPLAY 0.680851 (-2610 1335);
PAINT WHITE (-2610 1335);
WIRE 16 -1 (-4350 4700)(-4675 4700);
WIRE 16 -1 (-4625 1525)(-4625 1325);
WIRE 16 -1 (-4625 1325)(-3250 1325);
FORCEPROP 0 LAST SIG_NAME FM_CPU_RMCA_CATERR_LVT3_R_N
J 0
(-4500 1335);
DISPLAY 0.680851 (-4500 1335);
PAINT WHITE (-4500 1335);
WIRE 16 -1 (-4750 1325)(-4625 1325);
FORCEPROP 0 LAST CDS_PHYS_NET_NAME FM_CPU_RMCA_CATERR_LVT3_R_N
J 0
(-4650 1367);
PAINT MONO (-4650 1367);
DISPLAY INVISIBLE (-4650 1367);
DOT 1 (-1425 1775);
DOT 1 (-4625 1325);
FORCENOTE
20220119 CHANGE TO YELLOW LED
(-700 1625) 0;
DISPLAY LEFT (-700 1625);
DISPLAY 1.063830 (-700 1625);
PAINT WHITE (-700 1625);
FORCENOTE
20220119 CHANGE TO BLUE LED
(-4500 4500) 0;
DISPLAY LEFT (-4500 4500);
DISPLAY 1.063830 (-4500 4500);
PAINT WHITE (-4500 4500);
FORCENOTE
20210902 MODIFY FOR GT
(-6125 5475) 0;
DISPLAY LEFT (-6125 5475);
DISPLAY 2.510638 (-6125 5475);
PAINT PINK (-6125 5475);
QUIT
